(kicad_pcb
	(version 20260206)
	(generator "pcbnew")
	(generator_version "10.0")
	(general
		(thickness 1.6)
		(legacy_teardrops no)
	)
	(paper "A4")
	(title_block
		(title "Wiwynn_Tioga_Pass_MB.brd")
		(comment 1 "Tioga Pass / footprint 1441 of 4770 (J4G3), pads 1-123 of 291")
	)
	(layers
		(0 "F.Cu" signal "TOP")
		(4 "In1.Cu" signal "L2GND")
		(6 "In2.Cu" signal "L3")
		(8 "In3.Cu" signal "L4GND")
		(10 "In4.Cu" signal "L5")
		(12 "In5.Cu" signal "L6GND")
		(14 "In6.Cu" signal "L7VCC")
		(16 "In7.Cu" signal "L8VCC")
		(18 "In8.Cu" signal "L9GND")
		(20 "In9.Cu" signal "L10")
		(22 "In10.Cu" signal "L11GND")
		(24 "In11.Cu" signal "L12")
		(26 "In12.Cu" signal "L13GND")
		(2 "B.Cu" signal "BOTTOM")
		(9 "F.Adhes" user "F.Adhesive")
		(11 "B.Adhes" user "B.Adhesive")
		(13 "F.Paste" user "Package Geometry/Pastemask Top")
		(15 "B.Paste" user "Package Geometry/Pastemask Bottom")
		(5 "F.SilkS" user "Ref Des/Silkscreen Top")
		(7 "B.SilkS" user "Ref Des/Silkscreen Bottom")
		(1 "F.Mask" user "Board Geometry/Soldermask Top")
		(3 "B.Mask" user "Board Geometry/Soldermask Bottom")
		(17 "Dwgs.User" user "User.Drawings")
		(19 "Cmts.User" user "User.Comments")
		(21 "Eco1.User" user "User.Eco1")
		(23 "Eco2.User" user "User.Eco2")
		(25 "Edge.Cuts" user "Board Geometry/Outline")
		(27 "Margin" user)
		(31 "F.CrtYd" user "Package Geometry/Place Bound Top")
		(29 "B.CrtYd" user "Package Geometry/Place Bound Bottom")
		(35 "F.Fab" user "Ref Des/Assembly Top")
		(33 "B.Fab" user "Ref Des/Assembly Bottom")
	)
	(footprint ""
		(layer "F.Cu")
		(at 194.700398 3.778758 90)
		(property "Reference" "J4G3"
			(at 6.800088 37.20211 0)
			(unlocked yes)
			(layer "F.SilkS")
			(effects
				(font
					(size 0.7874 0.5842)
					(thickness 0.1524)
				)
				(justify left)
			)
		)
		(property "Value" ""
			(at 0 0 90)
			(layer "F.Fab")
			(effects
				(font
					(size 1.27 1.27)
				)
			)
		)
		(duplicate_pad_numbers_are_jumpers no)
		(pad "" thru_hole circle
			(at 2.29997 -5.649976 90)
			(size 2.8194 2.8194)
			(drill 2.4384)
			(layers "*.Cu" "*.Mask")
			(remove_unused_layers no)
			(clearance 0.127)
			(thermal_gap 0.127)
		)
		(pad "" thru_hole oval
			(at 2.29997 68.90004 90)
			(size 2.8194 1.5748)
			(drill oval 2.4384 1.1938)
			(layers "*.Cu" "*.Mask")
			(remove_unused_layers no)
			(clearance 0.127)
			(thermal_gap 0.127)
		)
		(pad "" thru_hole circle
			(at 2.29997 132.299964 90)
			(size 2.8194 2.8194)
			(drill 2.4384)
			(layers "*.Cu" "*.Mask")
			(remove_unused_layers no)
			(clearance 0.127)
			(thermal_gap 0.127)
		)
		(pad "1" smd rect
			(at 0 0 90)
			(size 1.8034 0.508)
			(layers "F.Cu" "F.Mask" "F.Paste")
			(net "P12V_NVDIMM_ABC")
		)
		(pad "2" smd rect
			(at 0 0.849884 90)
			(size 1.8034 0.508)
			(layers "F.Cu" "F.Mask" "F.Paste")
			(net "GND")
		)
		(pad "3" smd rect
			(at 0 1.700022 90)
			(size 1.8034 0.508)
			(layers "F.Cu" "F.Mask" "F.Paste")
			(net "M_C_DQ<5>")
		)
		(pad "4" smd rect
			(at 0 2.549906 90)
			(size 1.8034 0.508)
			(layers "F.Cu" "F.Mask" "F.Paste")
			(net "GND")
		)
		(pad "5" smd rect
			(at 0 3.400044 90)
			(size 1.8034 0.508)
			(layers "F.Cu" "F.Mask" "F.Paste")
			(net "M_C_DQ<1>")
		)
		(pad "6" smd rect
			(at 0 4.249928 90)
			(size 1.8034 0.508)
			(layers "F.Cu" "F.Mask" "F.Paste")
			(net "GND")
		)
		(pad "7" smd rect
			(at 0 5.100066 90)
			(size 1.8034 0.508)
			(layers "F.Cu" "F.Mask" "F.Paste")
			(net "M_C_DQS_DP<9>")
		)
		(pad "8" smd rect
			(at 0 5.94995 90)
			(size 1.8034 0.508)
			(layers "F.Cu" "F.Mask" "F.Paste")
			(net "M_C_DQS_DN<9>")
		)
		(pad "9" smd rect
			(at 0 6.800088 90)
			(size 1.8034 0.508)
			(layers "F.Cu" "F.Mask" "F.Paste")
			(net "GND")
		)
		(pad "10" smd rect
			(at 0 7.649972 90)
			(size 1.8034 0.508)
			(layers "F.Cu" "F.Mask" "F.Paste")
			(net "M_C_DQ<7>")
		)
		(pad "11" smd rect
			(at 0 8.50011 90)
			(size 1.8034 0.508)
			(layers "F.Cu" "F.Mask" "F.Paste")
			(net "GND")
		)
		(pad "12" smd rect
			(at 0 9.349994 90)
			(size 1.8034 0.508)
			(layers "F.Cu" "F.Mask" "F.Paste")
			(net "M_C_DQ<3>")
		)
		(pad "13" smd rect
			(at 0 10.199878 90)
			(size 1.8034 0.508)
			(layers "F.Cu" "F.Mask" "F.Paste")
			(net "GND")
		)
		(pad "14" smd rect
			(at 0 11.050016 90)
			(size 1.8034 0.508)
			(layers "F.Cu" "F.Mask" "F.Paste")
			(net "M_C_DQ<13>")
		)
		(pad "15" smd rect
			(at 0 11.8999 90)
			(size 1.8034 0.508)
			(layers "F.Cu" "F.Mask" "F.Paste")
			(net "GND")
		)
		(pad "16" smd rect
			(at 0 12.750038 90)
			(size 1.8034 0.508)
			(layers "F.Cu" "F.Mask" "F.Paste")
			(net "M_C_DQ<9>")
		)
		(pad "17" smd rect
			(at 0 13.599922 90)
			(size 1.8034 0.508)
			(layers "F.Cu" "F.Mask" "F.Paste")
			(net "GND")
		)
		(pad "18" smd rect
			(at 0 14.45006 90)
			(size 1.8034 0.508)
			(layers "F.Cu" "F.Mask" "F.Paste")
			(net "M_C_DQS_DP<10>")
		)
		(pad "19" smd rect
			(at 0 15.299944 90)
			(size 1.8034 0.508)
			(layers "F.Cu" "F.Mask" "F.Paste")
			(net "M_C_DQS_DN<10>")
		)
		(pad "20" smd rect
			(at 0 16.150082 90)
			(size 1.8034 0.508)
			(layers "F.Cu" "F.Mask" "F.Paste")
			(net "GND")
		)
		(pad "21" smd rect
			(at 0 16.999966 90)
			(size 1.8034 0.508)
			(layers "F.Cu" "F.Mask" "F.Paste")
			(net "M_C_DQ<15>")
		)
		(pad "22" smd rect
			(at 0 17.850104 90)
			(size 1.8034 0.508)
			(layers "F.Cu" "F.Mask" "F.Paste")
			(net "GND")
		)
		(pad "23" smd rect
			(at 0 18.699988 90)
			(size 1.8034 0.508)
			(layers "F.Cu" "F.Mask" "F.Paste")
			(net "M_C_DQ<11>")
		)
		(pad "24" smd rect
			(at 0 19.550126 90)
			(size 1.8034 0.508)
			(layers "F.Cu" "F.Mask" "F.Paste")
			(net "GND")
		)
		(pad "25" smd rect
			(at 0 20.40001 90)
			(size 1.8034 0.508)
			(layers "F.Cu" "F.Mask" "F.Paste")
			(net "M_C_DQ<21>")
		)
		(pad "26" smd rect
			(at 0 21.249894 90)
			(size 1.8034 0.508)
			(layers "F.Cu" "F.Mask" "F.Paste")
			(net "GND")
		)
		(pad "27" smd rect
			(at 0 22.100032 90)
			(size 1.8034 0.508)
			(layers "F.Cu" "F.Mask" "F.Paste")
			(net "M_C_DQ<17>")
		)
		(pad "28" smd rect
			(at 0 22.949916 90)
			(size 1.8034 0.508)
			(layers "F.Cu" "F.Mask" "F.Paste")
			(net "GND")
		)
		(pad "29" smd rect
			(at 0 23.800054 90)
			(size 1.8034 0.508)
			(layers "F.Cu" "F.Mask" "F.Paste")
			(net "M_C_DQS_DP<11>")
		)
		(pad "30" smd rect
			(at 0 24.649938 90)
			(size 1.8034 0.508)
			(layers "F.Cu" "F.Mask" "F.Paste")
			(net "M_C_DQS_DN<11>")
		)
		(pad "31" smd rect
			(at 0 25.500076 90)
			(size 1.8034 0.508)
			(layers "F.Cu" "F.Mask" "F.Paste")
			(net "GND")
		)
		(pad "32" smd rect
			(at 0 26.34996 90)
			(size 1.8034 0.508)
			(layers "F.Cu" "F.Mask" "F.Paste")
			(net "M_C_DQ<23>")
		)
		(pad "33" smd rect
			(at 0 27.200098 90)
			(size 1.8034 0.508)
			(layers "F.Cu" "F.Mask" "F.Paste")
			(net "GND")
		)
		(pad "34" smd rect
			(at 0 28.049982 90)
			(size 1.8034 0.508)
			(layers "F.Cu" "F.Mask" "F.Paste")
			(net "M_C_DQ<19>")
		)
		(pad "35" smd rect
			(at 0 28.90012 90)
			(size 1.8034 0.508)
			(layers "F.Cu" "F.Mask" "F.Paste")
			(net "GND")
		)
		(pad "36" smd rect
			(at 0 29.750004 90)
			(size 1.8034 0.508)
			(layers "F.Cu" "F.Mask" "F.Paste")
			(net "M_C_DQ<29>")
		)
		(pad "37" smd rect
			(at 0 30.599888 90)
			(size 1.8034 0.508)
			(layers "F.Cu" "F.Mask" "F.Paste")
			(net "GND")
		)
		(pad "38" smd rect
			(at 0 31.450026 90)
			(size 1.8034 0.508)
			(layers "F.Cu" "F.Mask" "F.Paste")
			(net "M_C_DQ<25>")
		)
		(pad "39" smd rect
			(at 0 32.29991 90)
			(size 1.8034 0.508)
			(layers "F.Cu" "F.Mask" "F.Paste")
			(net "GND")
		)
		(pad "40" smd rect
			(at 0 33.150048 90)
			(size 1.8034 0.508)
			(layers "F.Cu" "F.Mask" "F.Paste")
			(net "M_C_DQS_DP<12>")
		)
		(pad "41" smd rect
			(at 0 33.999932 90)
			(size 1.8034 0.508)
			(layers "F.Cu" "F.Mask" "F.Paste")
			(net "M_C_DQS_DN<12>")
		)
		(pad "42" smd rect
			(at 0 34.85007 90)
			(size 1.8034 0.508)
			(layers "F.Cu" "F.Mask" "F.Paste")
			(net "GND")
		)
		(pad "43" smd rect
			(at 0 35.699954 90)
			(size 1.8034 0.508)
			(layers "F.Cu" "F.Mask" "F.Paste")
			(net "M_C_DQ<31>")
		)
		(pad "44" smd rect
			(at 0 36.550092 90)
			(size 1.8034 0.508)
			(layers "F.Cu" "F.Mask" "F.Paste")
			(net "GND")
		)
		(pad "45" smd rect
			(at 0 37.399976 90)
			(size 1.8034 0.508)
			(layers "F.Cu" "F.Mask" "F.Paste")
			(net "M_C_DQ<27>")
		)
		(pad "46" smd rect
			(at 0 38.250114 90)
			(size 1.8034 0.508)
			(layers "F.Cu" "F.Mask" "F.Paste")
			(net "GND")
		)
		(pad "47" smd rect
			(at 0 39.099998 90)
			(size 1.8034 0.508)
			(layers "F.Cu" "F.Mask" "F.Paste")
			(net "M_C_ECC<5>")
		)
		(pad "48" smd rect
			(at 0 39.949882 90)
			(size 1.8034 0.508)
			(layers "F.Cu" "F.Mask" "F.Paste")
			(net "GND")
		)
		(pad "49" smd rect
			(at 0 40.80002 90)
			(size 1.8034 0.508)
			(layers "F.Cu" "F.Mask" "F.Paste")
			(net "M_C_ECC<1>")
		)
		(pad "50" smd rect
			(at 0 41.649904 90)
			(size 1.8034 0.508)
			(layers "F.Cu" "F.Mask" "F.Paste")
			(net "GND")
		)
		(pad "51" smd rect
			(at 0 42.500042 90)
			(size 1.8034 0.508)
			(layers "F.Cu" "F.Mask" "F.Paste")
			(net "M_C_DQS_DP<17>")
		)
		(pad "52" smd rect
			(at 0 43.349926 90)
			(size 1.8034 0.508)
			(layers "F.Cu" "F.Mask" "F.Paste")
			(net "M_C_DQS_DN<17>")
		)
		(pad "53" smd rect
			(at 0 44.200064 90)
			(size 1.8034 0.508)
			(layers "F.Cu" "F.Mask" "F.Paste")
			(net "GND")
		)
		(pad "54" smd rect
			(at 0 45.049948 90)
			(size 1.8034 0.508)
			(layers "F.Cu" "F.Mask" "F.Paste")
			(net "M_C_ECC<7>")
		)
		(pad "55" smd rect
			(at 0 45.900086 90)
			(size 1.8034 0.508)
			(layers "F.Cu" "F.Mask" "F.Paste")
			(net "GND")
		)
		(pad "56" smd rect
			(at 0 46.74997 90)
			(size 1.8034 0.508)
			(layers "F.Cu" "F.Mask" "F.Paste")
			(net "M_C_ECC<3>")
		)
		(pad "57" smd rect
			(at 0 47.600108 90)
			(size 1.8034 0.508)
			(layers "F.Cu" "F.Mask" "F.Paste")
			(net "GND")
		)
		(pad "58" smd rect
			(at 0 48.449992 90)
			(size 1.8034 0.508)
			(layers "F.Cu" "F.Mask" "F.Paste")
			(net "M_ABC_RST_N")
		)
		(pad "59" smd rect
			(at 0 49.299876 90)
			(size 1.8034 0.508)
			(layers "F.Cu" "F.Mask" "F.Paste")
			(net "PVDDQ_ABC")
		)
		(pad "60" smd rect
			(at 0 50.150014 90)
			(size 1.8034 0.508)
			(layers "F.Cu" "F.Mask" "F.Paste")
			(net "M_C_CKE<0>")
		)
		(pad "61" smd rect
			(at 0 50.999898 90)
			(size 1.8034 0.508)
			(layers "F.Cu" "F.Mask" "F.Paste")
			(net "PVDDQ_ABC")
		)
		(pad "62" smd rect
			(at 0 51.850036 90)
			(size 1.8034 0.508)
			(layers "F.Cu" "F.Mask" "F.Paste")
			(net "M_C_ACT_N")
		)
		(pad "63" smd rect
			(at 0 52.69992 90)
			(size 1.8034 0.508)
			(layers "F.Cu" "F.Mask" "F.Paste")
			(net "M_C_BG<0>")
		)
		(pad "64" smd rect
			(at 0 53.550058 90)
			(size 1.8034 0.508)
			(layers "F.Cu" "F.Mask" "F.Paste")
			(net "PVDDQ_ABC")
		)
		(pad "65" smd rect
			(at 0 54.399942 90)
			(size 1.8034 0.508)
			(layers "F.Cu" "F.Mask" "F.Paste")
			(net "M_C_MA<12>")
		)
		(pad "66" smd rect
			(at 0 55.25008 90)
			(size 1.8034 0.508)
			(layers "F.Cu" "F.Mask" "F.Paste")
			(net "M_C_MA<9>")
		)
		(pad "67" smd rect
			(at 0 56.099964 90)
			(size 1.8034 0.508)
			(layers "F.Cu" "F.Mask" "F.Paste")
			(net "PVDDQ_ABC")
		)
		(pad "68" smd rect
			(at 0 56.950102 90)
			(size 1.8034 0.508)
			(layers "F.Cu" "F.Mask" "F.Paste")
			(net "M_C_MA<8>")
		)
		(pad "69" smd rect
			(at 0 57.799986 90)
			(size 1.8034 0.508)
			(layers "F.Cu" "F.Mask" "F.Paste")
			(net "M_C_MA<6>")
		)
		(pad "70" smd rect
			(at 0 58.650124 90)
			(size 1.8034 0.508)
			(layers "F.Cu" "F.Mask" "F.Paste")
			(net "PVDDQ_ABC")
		)
		(pad "71" smd rect
			(at 0 59.500008 90)
			(size 1.8034 0.508)
			(layers "F.Cu" "F.Mask" "F.Paste")
			(net "M_C_MA<3>")
		)
		(pad "72" smd rect
			(at 0 60.349892 90)
			(size 1.8034 0.508)
			(layers "F.Cu" "F.Mask" "F.Paste")
			(net "M_C_MA<1>")
		)
		(pad "73" smd rect
			(at 0 61.20003 90)
			(size 1.8034 0.508)
			(layers "F.Cu" "F.Mask" "F.Paste")
			(net "PVDDQ_ABC")
		)
		(pad "74" smd rect
			(at 0 62.049914 90)
			(size 1.8034 0.508)
			(layers "F.Cu" "F.Mask" "F.Paste")
			(net "M_C_CLK_DP<0>")
		)
		(pad "75" smd rect
			(at 0 62.900052 90)
			(size 1.8034 0.508)
			(layers "F.Cu" "F.Mask" "F.Paste")
			(net "M_C_CLK_DN<0>")
		)
		(pad "76" smd rect
			(at 0 63.749936 90)
			(size 1.8034 0.508)
			(layers "F.Cu" "F.Mask" "F.Paste")
			(net "PVDDQ_ABC")
		)
		(pad "77" smd rect
			(at 0 64.600074 90)
			(size 1.8034 0.508)
			(layers "F.Cu" "F.Mask" "F.Paste")
			(net "PVTT_ABC")
		)
		(pad "78" smd rect
			(at 0 70.550024 90)
			(size 1.8034 0.508)
			(layers "F.Cu" "F.Mask" "F.Paste")
			(net "FM_DIMM_EVENT_COD_N")
		)
		(pad "79" smd rect
			(at 0 71.399908 90)
			(size 1.8034 0.508)
			(layers "F.Cu" "F.Mask" "F.Paste")
			(net "M_C_MA<0>")
		)
		(pad "80" smd rect
			(at 0 72.250046 90)
			(size 1.8034 0.508)
			(layers "F.Cu" "F.Mask" "F.Paste")
			(net "PVDDQ_ABC")
		)
		(pad "81" smd rect
			(at 0 73.09993 90)
			(size 1.8034 0.508)
			(layers "F.Cu" "F.Mask" "F.Paste")
			(net "M_C_BA<0>")
		)
		(pad "82" smd rect
			(at 0 73.950068 90)
			(size 1.8034 0.508)
			(layers "F.Cu" "F.Mask" "F.Paste")
			(net "M_C_MA<16>")
		)
		(pad "83" smd rect
			(at 0 74.799952 90)
			(size 1.8034 0.508)
			(layers "F.Cu" "F.Mask" "F.Paste")
			(net "PVDDQ_ABC")
		)
		(pad "84" smd rect
			(at 0 75.65009 90)
			(size 1.8034 0.508)
			(layers "F.Cu" "F.Mask" "F.Paste")
			(net "M_C_CS_N<0>")
		)
		(pad "85" smd rect
			(at 0 76.499974 90)
			(size 1.8034 0.508)
			(layers "F.Cu" "F.Mask" "F.Paste")
			(net "PVDDQ_ABC")
		)
		(pad "86" smd rect
			(at 0 77.350112 90)
			(size 1.8034 0.508)
			(layers "F.Cu" "F.Mask" "F.Paste")
			(net "M_C_MA<15>")
		)
		(pad "87" smd rect
			(at 0 78.199996 90)
			(size 1.8034 0.508)
			(layers "F.Cu" "F.Mask" "F.Paste")
			(net "M_C_ODT<0>")
		)
		(pad "88" smd rect
			(at 0 79.04988 90)
			(size 1.8034 0.508)
			(layers "F.Cu" "F.Mask" "F.Paste")
			(net "PVDDQ_ABC")
		)
		(pad "89" smd rect
			(at 0 79.900018 90)
			(size 1.8034 0.508)
			(layers "F.Cu" "F.Mask" "F.Paste")
			(net "M_C_CS_N<1>")
		)
		(pad "90" smd rect
			(at 0 80.749902 90)
			(size 1.8034 0.508)
			(layers "F.Cu" "F.Mask" "F.Paste")
			(net "PVDDQ_ABC")
		)
		(pad "91" smd rect
			(at 0 81.60004 90)
			(size 1.8034 0.508)
			(layers "F.Cu" "F.Mask" "F.Paste")
			(net "M_C_ODT<1>")
		)
		(pad "92" smd rect
			(at 0 82.449924 90)
			(size 1.8034 0.508)
			(layers "F.Cu" "F.Mask" "F.Paste")
			(net "PVDDQ_ABC")
		)
		(pad "93" smd rect
			(at 0 83.300062 90)
			(size 1.8034 0.508)
			(layers "F.Cu" "F.Mask" "F.Paste")
			(net "M_C_CS_N<2>")
		)
		(pad "94" smd rect
			(at 0 84.149946 90)
			(size 1.8034 0.508)
			(layers "F.Cu" "F.Mask" "F.Paste")
			(net "GND")
		)
		(pad "95" smd rect
			(at 0 85.000084 90)
			(size 1.8034 0.508)
			(layers "F.Cu" "F.Mask" "F.Paste")
			(net "M_C_DQ<37>")
		)
		(pad "96" smd rect
			(at 0 85.849968 90)
			(size 1.8034 0.508)
			(layers "F.Cu" "F.Mask" "F.Paste")
			(net "GND")
		)
		(pad "97" smd rect
			(at 0 86.700106 90)
			(size 1.8034 0.508)
			(layers "F.Cu" "F.Mask" "F.Paste")
			(net "M_C_DQ<33>")
		)
		(pad "98" smd rect
			(at 0 87.54999 90)
			(size 1.8034 0.508)
			(layers "F.Cu" "F.Mask" "F.Paste")
			(net "GND")
		)
		(pad "99" smd rect
			(at 0 88.399874 90)
			(size 1.8034 0.508)
			(layers "F.Cu" "F.Mask" "F.Paste")
			(net "M_C_DQS_DP<13>")
		)
		(pad "100" smd rect
			(at 0 89.250012 90)
			(size 1.8034 0.508)
			(layers "F.Cu" "F.Mask" "F.Paste")
			(net "M_C_DQS_DN<13>")
		)
		(pad "101" smd rect
			(at 0 90.099896 90)
			(size 1.8034 0.508)
			(layers "F.Cu" "F.Mask" "F.Paste")
			(net "GND")
		)
		(pad "102" smd rect
			(at 0 90.950034 90)
			(size 1.8034 0.508)
			(layers "F.Cu" "F.Mask" "F.Paste")
			(net "M_C_DQ<39>")
		)
		(pad "103" smd rect
			(at 0 91.799918 90)
			(size 1.8034 0.508)
			(layers "F.Cu" "F.Mask" "F.Paste")
			(net "GND")
		)
		(pad "104" smd rect
			(at 0 92.650056 90)
			(size 1.8034 0.508)
			(layers "F.Cu" "F.Mask" "F.Paste")
			(net "M_C_DQ<35>")
		)
		(pad "105" smd rect
			(at 0 93.49994 90)
			(size 1.8034 0.508)
			(layers "F.Cu" "F.Mask" "F.Paste")
			(net "GND")
		)
		(pad "106" smd rect
			(at 0 94.350078 90)
			(size 1.8034 0.508)
			(layers "F.Cu" "F.Mask" "F.Paste")
			(net "M_C_DQ<45>")
		)
		(pad "107" smd rect
			(at 0 95.199962 90)
			(size 1.8034 0.508)
			(layers "F.Cu" "F.Mask" "F.Paste")
			(net "GND")
		)
		(pad "108" smd rect
			(at 0 96.0501 90)
			(size 1.8034 0.508)
			(layers "F.Cu" "F.Mask" "F.Paste")
			(net "M_C_DQ<41>")
		)
		(pad "109" smd rect
			(at 0 96.899984 90)
			(size 1.8034 0.508)
			(layers "F.Cu" "F.Mask" "F.Paste")
			(net "GND")
		)
		(pad "110" smd rect
			(at 0 97.750122 90)
			(size 1.8034 0.508)
			(layers "F.Cu" "F.Mask" "F.Paste")
			(net "M_C_DQS_DP<14>")
		)
		(pad "111" smd rect
			(at 0 98.600006 90)
			(size 1.8034 0.508)
			(layers "F.Cu" "F.Mask" "F.Paste")
			(net "M_C_DQS_DN<14>")
		)
		(pad "112" smd rect
			(at 0 99.44989 90)
			(size 1.8034 0.508)
			(layers "F.Cu" "F.Mask" "F.Paste")
			(net "GND")
		)
		(pad "113" smd rect
			(at 0 100.300028 90)
			(size 1.8034 0.508)
			(layers "F.Cu" "F.Mask" "F.Paste")
			(net "M_C_DQ<47>")
		)
		(pad "114" smd rect
			(at 0 101.149912 90)
			(size 1.8034 0.508)
			(layers "F.Cu" "F.Mask" "F.Paste")
			(net "GND")
		)
		(pad "115" smd rect
			(at 0 102.00005 90)
			(size 1.8034 0.508)
			(layers "F.Cu" "F.Mask" "F.Paste")
			(net "M_C_DQ<43>")
		)
		(pad "116" smd rect
			(at 0 102.849934 90)
			(size 1.8034 0.508)
			(layers "F.Cu" "F.Mask" "F.Paste")
			(net "GND")
		)
		(pad "117" smd rect
			(at 0 103.700072 90)
			(size 1.8034 0.508)
			(layers "F.Cu" "F.Mask" "F.Paste")
			(net "M_C_DQ<53>")
		)
		(pad "118" smd rect
			(at 0 104.549956 90)
			(size 1.8034 0.508)
			(layers "F.Cu" "F.Mask" "F.Paste")
			(net "GND")
		)
		(pad "119" smd rect
			(at 0 105.400094 90)
			(size 1.8034 0.508)
			(layers "F.Cu" "F.Mask" "F.Paste")
			(net "M_C_DQ<49>")
		)
		(pad "120" smd rect
			(at 0 106.249978 90)
			(size 1.8034 0.508)
			(layers "F.Cu" "F.Mask" "F.Paste")
			(net "GND")
		)
	)
)
